(kicad_pcb
	(version 20260206)
	(generator "pcbnew")
	(generator_version "10.0")
	(general
		(thickness 1.6)
		(legacy_teardrops no)
	)
	(paper "A4")
	(title_block
		(title "12092022_DA0F0TFB6D0_F0T_FAN_BOARD_MP5048_D_brd_v02_OCP.brd")
		(comment 1 "Grand Teton / footprints 44-49 of 924")
	)
	(layers
		(0 "F.Cu" signal "TOP")
		(4 "In1.Cu" signal "GND")
		(6 "In2.Cu" signal "IN1")
		(8 "In3.Cu" signal "IN2")
		(10 "In4.Cu" signal "GND1")
		(2 "B.Cu" signal "BOTTOM")
		(9 "F.Adhes" user "F.Adhesive")
		(11 "B.Adhes" user "B.Adhesive")
		(13 "F.Paste" user "Package Geometry/Pastemask Top")
		(15 "B.Paste" user "Package Geometry/Pastemask Bottom")
		(5 "F.SilkS" user "Ref Des/Silkscreen Top")
		(7 "B.SilkS" user "Ref Des/Silkscreen Bottom")
		(1 "F.Mask" user "Board Geometry/Soldermask Top")
		(3 "B.Mask" user "Board Geometry/Soldermask Bottom")
		(17 "Dwgs.User" user "User.Drawings")
		(19 "Cmts.User" user "User.Comments")
		(21 "Eco1.User" user "User.Eco1")
		(23 "Eco2.User" user "User.Eco2")
		(25 "Edge.Cuts" user "Board Geometry/Outline")
		(27 "Margin" user)
		(31 "F.CrtYd" user "Package Geometry/Place Bound Top")
		(29 "B.CrtYd" user "Package Geometry/Place Bound Bottom")
		(35 "F.Fab" user "Ref Des/Assembly Top")
		(33 "B.Fab" user "Ref Des/Assembly Bottom")
	)
	(footprint ""
		(layer "F.Cu")
		(at 28.575 -287.02 90)
		(property "Reference" "R5518"
			(at 0 0 90)
			(layer "F.SilkS")
			(hide yes)
			(effects
				(font
					(size 1.27 1.27)
				)
			)
		)
		(property "Value" ""
			(at 0 0 90)
			(layer "F.Fab")
			(effects
				(font
					(size 1.27 1.27)
				)
			)
		)
		(duplicate_pad_numbers_are_jumpers no)
		(fp_line
			(start 0.7874 -0.4064)
			(end 0.7874 0.4064)
			(stroke
				(width 0.1524)
				(type default)
			)
			(layer "F.SilkS")
		)
		(fp_line
			(start -0.7874 -0.4064)
			(end 0.7874 -0.4064)
			(stroke
				(width 0.1524)
				(type default)
			)
			(layer "F.SilkS")
		)
		(fp_line
			(start 0.7874 0.4064)
			(end -0.7874 0.4064)
			(stroke
				(width 0.1524)
				(type default)
			)
			(layer "F.SilkS")
		)
		(fp_line
			(start -0.7874 0.4064)
			(end -0.7874 -0.4064)
			(stroke
				(width 0.1524)
				(type default)
			)
			(layer "F.SilkS")
		)
		(fp_line
			(start -0.12065 -0.305054)
			(end -0.12065 -0.2794)
			(stroke
				(width 0.1)
				(type default)
			)
			(layer "F.Fab")
		)
		(fp_line
			(start -0.67945 -0.305054)
			(end -0.12065 -0.305054)
			(stroke
				(width 0.1)
				(type default)
			)
			(layer "F.Fab")
		)
		(fp_line
			(start 0.67945 -0.3048)
			(end 0.67945 0.3048)
			(stroke
				(width 0.1)
				(type default)
			)
			(layer "F.Fab")
		)
		(fp_line
			(start 0.12065 -0.3048)
			(end 0.67945 -0.3048)
			(stroke
				(width 0.1)
				(type default)
			)
			(layer "F.Fab")
		)
		(fp_line
			(start 0.12065 -0.2794)
			(end 0.12065 -0.3048)
			(stroke
				(width 0.1)
				(type default)
			)
			(layer "F.Fab")
		)
		(fp_line
			(start -0.12065 -0.2794)
			(end 0.12065 -0.2794)
			(stroke
				(width 0.1)
				(type default)
			)
			(layer "F.Fab")
		)
		(fp_line
			(start 0.120396 0.2794)
			(end -0.12065 0.2794)
			(stroke
				(width 0.1)
				(type default)
			)
			(layer "F.Fab")
		)
		(fp_line
			(start -0.12065 0.2794)
			(end -0.12065 0.3048)
			(stroke
				(width 0.1)
				(type default)
			)
			(layer "F.Fab")
		)
		(fp_line
			(start 0.67945 0.3048)
			(end 0.120396 0.3048)
			(stroke
				(width 0.1)
				(type default)
			)
			(layer "F.Fab")
		)
		(fp_line
			(start 0.120396 0.3048)
			(end 0.120396 0.2794)
			(stroke
				(width 0.1)
				(type default)
			)
			(layer "F.Fab")
		)
		(fp_line
			(start -0.12065 0.3048)
			(end -0.67945 0.3048)
			(stroke
				(width 0.1)
				(type default)
			)
			(layer "F.Fab")
		)
		(fp_line
			(start -0.67945 0.3048)
			(end -0.67945 -0.305054)
			(stroke
				(width 0.1)
				(type default)
			)
			(layer "F.Fab")
		)
		(pad "1" smd circle
			(at -0.40005 0 90)
			(size 0 0)
			(layers "F.Cu" "F.Mask" "F.Paste")
			(net "P3V3_AUX")
		)
		(pad "2" smd circle
			(at 0.40005 0 90)
			(size 0 0)
			(layers "F.Cu" "F.Mask" "F.Paste")
			(net "FAN_7_PWM_BUF")
		)
	)
	(footprint ""
		(layer "F.Cu")
		(at 27.686 -121.92 90)
		(property "Reference" "R5681"
			(at 0 0 90)
			(layer "F.SilkS")
			(hide yes)
			(effects
				(font
					(size 1.27 1.27)
				)
			)
		)
		(property "Value" ""
			(at 0 0 90)
			(layer "F.Fab")
			(effects
				(font
					(size 1.27 1.27)
				)
			)
		)
		(duplicate_pad_numbers_are_jumpers no)
		(fp_line
			(start 0.7874 -0.4064)
			(end 0.7874 0.4064)
			(stroke
				(width 0.1524)
				(type default)
			)
			(layer "F.SilkS")
		)
		(fp_line
			(start -0.7874 -0.4064)
			(end 0.7874 -0.4064)
			(stroke
				(width 0.1524)
				(type default)
			)
			(layer "F.SilkS")
		)
		(fp_line
			(start 0.7874 0.4064)
			(end -0.7874 0.4064)
			(stroke
				(width 0.1524)
				(type default)
			)
			(layer "F.SilkS")
		)
		(fp_line
			(start -0.7874 0.4064)
			(end -0.7874 -0.4064)
			(stroke
				(width 0.1524)
				(type default)
			)
			(layer "F.SilkS")
		)
		(fp_line
			(start -0.12065 -0.305054)
			(end -0.12065 -0.2794)
			(stroke
				(width 0.1)
				(type default)
			)
			(layer "F.Fab")
		)
		(fp_line
			(start -0.67945 -0.305054)
			(end -0.12065 -0.305054)
			(stroke
				(width 0.1)
				(type default)
			)
			(layer "F.Fab")
		)
		(fp_line
			(start 0.67945 -0.3048)
			(end 0.67945 0.3048)
			(stroke
				(width 0.1)
				(type default)
			)
			(layer "F.Fab")
		)
		(fp_line
			(start 0.12065 -0.3048)
			(end 0.67945 -0.3048)
			(stroke
				(width 0.1)
				(type default)
			)
			(layer "F.Fab")
		)
		(fp_line
			(start 0.12065 -0.2794)
			(end 0.12065 -0.3048)
			(stroke
				(width 0.1)
				(type default)
			)
			(layer "F.Fab")
		)
		(fp_line
			(start -0.12065 -0.2794)
			(end 0.12065 -0.2794)
			(stroke
				(width 0.1)
				(type default)
			)
			(layer "F.Fab")
		)
		(fp_line
			(start 0.120396 0.2794)
			(end -0.12065 0.2794)
			(stroke
				(width 0.1)
				(type default)
			)
			(layer "F.Fab")
		)
		(fp_line
			(start -0.12065 0.2794)
			(end -0.12065 0.3048)
			(stroke
				(width 0.1)
				(type default)
			)
			(layer "F.Fab")
		)
		(fp_line
			(start 0.67945 0.3048)
			(end 0.120396 0.3048)
			(stroke
				(width 0.1)
				(type default)
			)
			(layer "F.Fab")
		)
		(fp_line
			(start 0.120396 0.3048)
			(end 0.120396 0.2794)
			(stroke
				(width 0.1)
				(type default)
			)
			(layer "F.Fab")
		)
		(fp_line
			(start -0.12065 0.3048)
			(end -0.67945 0.3048)
			(stroke
				(width 0.1)
				(type default)
			)
			(layer "F.Fab")
		)
		(fp_line
			(start -0.67945 0.3048)
			(end -0.67945 -0.305054)
			(stroke
				(width 0.1)
				(type default)
			)
			(layer "F.Fab")
		)
		(pad "1" smd circle
			(at -0.40005 0 90)
			(size 0 0)
			(layers "F.Cu" "F.Mask" "F.Paste")
			(net "P3V3_AUX")
		)
		(pad "2" smd circle
			(at 0.40005 0 90)
			(size 0 0)
			(layers "F.Cu" "F.Mask" "F.Paste")
			(net "U317_FAN FAIL_N")
		)
	)
	(footprint ""
		(layer "F.Cu")
		(at 32.512 -302.895)
		(property "Reference" "R5300"
			(at 0 0 0)
			(layer "F.SilkS")
			(hide yes)
			(effects
				(font
					(size 1.27 1.27)
				)
			)
		)
		(property "Value" ""
			(at 0 0 0)
			(layer "F.Fab")
			(effects
				(font
					(size 1.27 1.27)
				)
			)
		)
		(duplicate_pad_numbers_are_jumpers no)
		(fp_line
			(start -1.2954 -0.5842)
			(end 1.2954 -0.5842)
			(stroke
				(width 0.1524)
				(type default)
			)
			(layer "F.SilkS")
		)
		(fp_line
			(start -1.2954 0.5842)
			(end -1.2954 -0.5842)
			(stroke
				(width 0.1524)
				(type default)
			)
			(layer "F.SilkS")
		)
		(fp_line
			(start 1.2954 -0.5842)
			(end 1.2954 0.5842)
			(stroke
				(width 0.1524)
				(type default)
			)
			(layer "F.SilkS")
		)
		(fp_line
			(start 1.2954 0.5842)
			(end -1.2954 0.5842)
			(stroke
				(width 0.1524)
				(type default)
			)
			(layer "F.SilkS")
		)
		(fp_line
			(start -1.1938 -0.406654)
			(end -0.8636 -0.406654)
			(stroke
				(width 0.1)
				(type default)
			)
			(layer "F.Fab")
		)
		(fp_line
			(start -1.1938 0.4064)
			(end -1.1938 -0.406654)
			(stroke
				(width 0.1)
				(type default)
			)
			(layer "F.Fab")
		)
		(fp_line
			(start -0.8636 -0.4572)
			(end 0.8636 -0.4572)
			(stroke
				(width 0.1)
				(type default)
			)
			(layer "F.Fab")
		)
		(fp_line
			(start -0.8636 -0.406654)
			(end -0.8636 -0.4572)
			(stroke
				(width 0.1)
				(type default)
			)
			(layer "F.Fab")
		)
		(fp_line
			(start -0.8636 0.4064)
			(end -1.1938 0.4064)
			(stroke
				(width 0.1)
				(type default)
			)
			(layer "F.Fab")
		)
		(fp_line
			(start -0.8636 0.4318)
			(end -0.8636 0.4064)
			(stroke
				(width 0.1)
				(type default)
			)
			(layer "F.Fab")
		)
		(fp_line
			(start -0.8636 0.4572)
			(end -0.8636 0.4318)
			(stroke
				(width 0.1)
				(type default)
			)
			(layer "F.Fab")
		)
		(fp_line
			(start 0.8636 -0.4572)
			(end 0.8636 -0.406654)
			(stroke
				(width 0.1)
				(type default)
			)
			(layer "F.Fab")
		)
		(fp_line
			(start 0.8636 -0.406654)
			(end 1.1938 -0.406654)
			(stroke
				(width 0.1)
				(type default)
			)
			(layer "F.Fab")
		)
		(fp_line
			(start 0.8636 0.4064)
			(end 0.8636 0.4572)
			(stroke
				(width 0.1)
				(type default)
			)
			(layer "F.Fab")
		)
		(fp_line
			(start 0.8636 0.4572)
			(end -0.8636 0.4572)
			(stroke
				(width 0.1)
				(type default)
			)
			(layer "F.Fab")
		)
		(fp_line
			(start 1.1938 -0.406654)
			(end 1.1938 0.4064)
			(stroke
				(width 0.1)
				(type default)
			)
			(layer "F.Fab")
		)
		(fp_line
			(start 1.1938 0.4064)
			(end 0.8636 0.4064)
			(stroke
				(width 0.1)
				(type default)
			)
			(layer "F.Fab")
		)
		(pad "1" smd rect
			(at -0.7366 0 270)
			(size 0.7112 0.8128)
			(layers "F.Cu" "F.Mask" "F.Paste")
			(net "P52V_FAN_0")
		)
		(pad "2" smd rect
			(at 0.7366 0 270)
			(size 0.7112 0.8128)
			(layers "F.Cu" "F.Mask" "F.Paste")
			(net "FAN_0_TACH_IL_R")
		)
	)
	(footprint ""
		(layer "F.Cu")
		(at 14.351 -73.914 90)
		(property "Reference" "PR56"
			(at 0 0 90)
			(layer "F.SilkS")
			(hide yes)
			(effects
				(font
					(size 1.27 1.27)
				)
			)
		)
		(property "Value" ""
			(at 0 0 90)
			(layer "F.Fab")
			(effects
				(font
					(size 1.27 1.27)
				)
			)
		)
		(duplicate_pad_numbers_are_jumpers no)
		(fp_line
			(start 0.7874 -0.4064)
			(end 0.7874 0.4064)
			(stroke
				(width 0.1524)
				(type default)
			)
			(layer "F.SilkS")
		)
		(fp_line
			(start -0.7874 -0.4064)
			(end 0.7874 -0.4064)
			(stroke
				(width 0.1524)
				(type default)
			)
			(layer "F.SilkS")
		)
		(fp_line
			(start 0.7874 0.4064)
			(end -0.7874 0.4064)
			(stroke
				(width 0.1524)
				(type default)
			)
			(layer "F.SilkS")
		)
		(fp_line
			(start -0.7874 0.4064)
			(end -0.7874 -0.4064)
			(stroke
				(width 0.1524)
				(type default)
			)
			(layer "F.SilkS")
		)
		(fp_line
			(start -0.12065 -0.305054)
			(end -0.12065 -0.2794)
			(stroke
				(width 0.1)
				(type default)
			)
			(layer "F.Fab")
		)
		(fp_line
			(start -0.67945 -0.305054)
			(end -0.12065 -0.305054)
			(stroke
				(width 0.1)
				(type default)
			)
			(layer "F.Fab")
		)
		(fp_line
			(start 0.67945 -0.3048)
			(end 0.67945 0.3048)
			(stroke
				(width 0.1)
				(type default)
			)
			(layer "F.Fab")
		)
		(fp_line
			(start 0.12065 -0.3048)
			(end 0.67945 -0.3048)
			(stroke
				(width 0.1)
				(type default)
			)
			(layer "F.Fab")
		)
		(fp_line
			(start 0.12065 -0.2794)
			(end 0.12065 -0.3048)
			(stroke
				(width 0.1)
				(type default)
			)
			(layer "F.Fab")
		)
		(fp_line
			(start -0.12065 -0.2794)
			(end 0.12065 -0.2794)
			(stroke
				(width 0.1)
				(type default)
			)
			(layer "F.Fab")
		)
		(fp_line
			(start 0.120396 0.2794)
			(end -0.12065 0.2794)
			(stroke
				(width 0.1)
				(type default)
			)
			(layer "F.Fab")
		)
		(fp_line
			(start -0.12065 0.2794)
			(end -0.12065 0.3048)
			(stroke
				(width 0.1)
				(type default)
			)
			(layer "F.Fab")
		)
		(fp_line
			(start 0.67945 0.3048)
			(end 0.120396 0.3048)
			(stroke
				(width 0.1)
				(type default)
			)
			(layer "F.Fab")
		)
		(fp_line
			(start 0.120396 0.3048)
			(end 0.120396 0.2794)
			(stroke
				(width 0.1)
				(type default)
			)
			(layer "F.Fab")
		)
		(fp_line
			(start -0.12065 0.3048)
			(end -0.67945 0.3048)
			(stroke
				(width 0.1)
				(type default)
			)
			(layer "F.Fab")
		)
		(fp_line
			(start -0.67945 0.3048)
			(end -0.67945 -0.305054)
			(stroke
				(width 0.1)
				(type default)
			)
			(layer "F.Fab")
		)
		(pad "1" smd rect
			(at -0.40005 0 270)
			(size 0.4572 0.508)
			(layers "F.Cu" "F.Mask" "F.Paste")
			(net "FAN_5_FAULT_R")
		)
		(pad "2" smd rect
			(at 0.40005 0 270)
			(size 0.4572 0.508)
			(layers "F.Cu" "F.Mask" "F.Paste")
			(net "FAN_5_FAULT")
		)
	)
	(footprint ""
		(layer "F.Cu")
		(at 45.085 -186.182)
		(property "Reference" "R5494"
			(at 0 0 0)
			(layer "F.SilkS")
			(hide yes)
			(effects
				(font
					(size 1.27 1.27)
				)
			)
		)
		(property "Value" ""
			(at 0 0 0)
			(layer "F.Fab")
			(effects
				(font
					(size 1.27 1.27)
				)
			)
		)
		(duplicate_pad_numbers_are_jumpers no)
		(fp_line
			(start -0.7874 -0.4064)
			(end 0.7874 -0.4064)
			(stroke
				(width 0.1524)
				(type default)
			)
			(layer "F.SilkS")
		)
		(fp_line
			(start -0.7874 0.4064)
			(end -0.7874 -0.4064)
			(stroke
				(width 0.1524)
				(type default)
			)
			(layer "F.SilkS")
		)
		(fp_line
			(start 0.7874 -0.4064)
			(end 0.7874 0.4064)
			(stroke
				(width 0.1524)
				(type default)
			)
			(layer "F.SilkS")
		)
		(fp_line
			(start 0.7874 0.4064)
			(end -0.7874 0.4064)
			(stroke
				(width 0.1524)
				(type default)
			)
			(layer "F.SilkS")
		)
		(fp_line
			(start -0.67945 -0.305054)
			(end -0.12065 -0.305054)
			(stroke
				(width 0.1)
				(type default)
			)
			(layer "F.Fab")
		)
		(fp_line
			(start -0.67945 0.3048)
			(end -0.67945 -0.305054)
			(stroke
				(width 0.1)
				(type default)
			)
			(layer "F.Fab")
		)
		(fp_line
			(start -0.12065 -0.305054)
			(end -0.12065 -0.2794)
			(stroke
				(width 0.1)
				(type default)
			)
			(layer "F.Fab")
		)
		(fp_line
			(start -0.12065 -0.2794)
			(end 0.12065 -0.2794)
			(stroke
				(width 0.1)
				(type default)
			)
			(layer "F.Fab")
		)
		(fp_line
			(start -0.12065 0.2794)
			(end -0.12065 0.3048)
			(stroke
				(width 0.1)
				(type default)
			)
			(layer "F.Fab")
		)
		(fp_line
			(start -0.12065 0.3048)
			(end -0.67945 0.3048)
			(stroke
				(width 0.1)
				(type default)
			)
			(layer "F.Fab")
		)
		(fp_line
			(start 0.120396 0.2794)
			(end -0.12065 0.2794)
			(stroke
				(width 0.1)
				(type default)
			)
			(layer "F.Fab")
		)
		(fp_line
			(start 0.120396 0.3048)
			(end 0.120396 0.2794)
			(stroke
				(width 0.1)
				(type default)
			)
			(layer "F.Fab")
		)
		(fp_line
			(start 0.12065 -0.3048)
			(end 0.67945 -0.3048)
			(stroke
				(width 0.1)
				(type default)
			)
			(layer "F.Fab")
		)
		(fp_line
			(start 0.12065 -0.2794)
			(end 0.12065 -0.3048)
			(stroke
				(width 0.1)
				(type default)
			)
			(layer "F.Fab")
		)
		(fp_line
			(start 0.67945 -0.3048)
			(end 0.67945 0.3048)
			(stroke
				(width 0.1)
				(type default)
			)
			(layer "F.Fab")
		)
		(fp_line
			(start 0.67945 0.3048)
			(end 0.120396 0.3048)
			(stroke
				(width 0.1)
				(type default)
			)
			(layer "F.Fab")
		)
		(pad "1" smd circle
			(at -0.40005 0)
			(size 0 0)
			(layers "F.Cu" "F.Mask" "F.Paste")
			(net "P52V_FAN_7_BUFF_EN")
		)
		(pad "2" smd circle
			(at 0.40005 0)
			(size 0 0)
			(layers "F.Cu" "F.Mask" "F.Paste")
			(net "P52V_FAN_7_BUFF_EN_R")
		)
	)
	(footprint ""
		(layer "F.Cu")
		(at 35.179 -162.941 90)
		(property "Reference" "R5269"
			(at 0 0 90)
			(layer "F.SilkS")
			(hide yes)
			(effects
				(font
					(size 1.27 1.27)
				)
			)
		)
		(property "Value" ""
			(at 0 0 90)
			(layer "F.Fab")
			(effects
				(font
					(size 1.27 1.27)
				)
			)
		)
		(duplicate_pad_numbers_are_jumpers no)
		(fp_line
			(start 0.7874 -0.4064)
			(end 0.7874 0.4064)
			(stroke
				(width 0.1524)
				(type default)
			)
			(layer "F.SilkS")
		)
		(fp_line
			(start -0.7874 -0.4064)
			(end 0.7874 -0.4064)
			(stroke
				(width 0.1524)
				(type default)
			)
			(layer "F.SilkS")
		)
		(fp_line
			(start 0.7874 0.4064)
			(end -0.7874 0.4064)
			(stroke
				(width 0.1524)
				(type default)
			)
			(layer "F.SilkS")
		)
		(fp_line
			(start -0.7874 0.4064)
			(end -0.7874 -0.4064)
			(stroke
				(width 0.1524)
				(type default)
			)
			(layer "F.SilkS")
		)
		(fp_line
			(start -0.12065 -0.305054)
			(end -0.12065 -0.2794)
			(stroke
				(width 0.1)
				(type default)
			)
			(layer "F.Fab")
		)
		(fp_line
			(start -0.67945 -0.305054)
			(end -0.12065 -0.305054)
			(stroke
				(width 0.1)
				(type default)
			)
			(layer "F.Fab")
		)
		(fp_line
			(start 0.67945 -0.3048)
			(end 0.67945 0.3048)
			(stroke
				(width 0.1)
				(type default)
			)
			(layer "F.Fab")
		)
		(fp_line
			(start 0.12065 -0.3048)
			(end 0.67945 -0.3048)
			(stroke
				(width 0.1)
				(type default)
			)
			(layer "F.Fab")
		)
		(fp_line
			(start 0.12065 -0.2794)
			(end 0.12065 -0.3048)
			(stroke
				(width 0.1)
				(type default)
			)
			(layer "F.Fab")
		)
		(fp_line
			(start -0.12065 -0.2794)
			(end 0.12065 -0.2794)
			(stroke
				(width 0.1)
				(type default)
			)
			(layer "F.Fab")
		)
		(fp_line
			(start 0.120396 0.2794)
			(end -0.12065 0.2794)
			(stroke
				(width 0.1)
				(type default)
			)
			(layer "F.Fab")
		)
		(fp_line
			(start -0.12065 0.2794)
			(end -0.12065 0.3048)
			(stroke
				(width 0.1)
				(type default)
			)
			(layer "F.Fab")
		)
		(fp_line
			(start 0.67945 0.3048)
			(end 0.120396 0.3048)
			(stroke
				(width 0.1)
				(type default)
			)
			(layer "F.Fab")
		)
		(fp_line
			(start 0.120396 0.3048)
			(end 0.120396 0.2794)
			(stroke
				(width 0.1)
				(type default)
			)
			(layer "F.Fab")
		)
		(fp_line
			(start -0.12065 0.3048)
			(end -0.67945 0.3048)
			(stroke
				(width 0.1)
				(type default)
			)
			(layer "F.Fab")
		)
		(fp_line
			(start -0.67945 0.3048)
			(end -0.67945 -0.305054)
			(stroke
				(width 0.1)
				(type default)
			)
			(layer "F.Fab")
		)
		(pad "1" smd circle
			(at -0.40005 0 90)
			(size 0 0)
			(layers "F.Cu" "F.Mask" "F.Paste")
			(net "SMB_FAN4_R_SDA")
		)
		(pad "2" smd circle
			(at 0.40005 0 90)
			(size 0 0)
			(layers "F.Cu" "F.Mask" "F.Paste")
			(net "P3V3_AUX")
		)
	)
)
